# T6G (Grand Teton) — schematic netlist excerpt (pin names and nets, part order shuffled) for the footprints in the layout excerpt that follows; sources: Cadence DE-HDL packaged netlist, KiCad conversion of 04192023_DAF0TMB3IC0_F0TG_MB_C_brd_V02_OCP.brd

PR6814  Q_RES  10K 1% EMPTY  pkg 0402LF  page 362 : A = P0V9_RETIMER_CPU0_TEMP0 ; B = GND
C1032  Q_CAP  22UF 4V 20% X6S  pkg C0402  page 312 : A = P0V9_CPU0_RT_2D ; B = GND

(kicad_pcb
	(version 20260206)
	(generator "pcbnew")
	(generator_version "10.0")
	(general
		(thickness 1.6)
		(legacy_teardrops no)
	)
	(paper "A4")
	(title_block
		(title "04192023_DAF0TMB3IC0_F0TG_MB_C_brd_V02_OCP.brd")
		(comment 1 "Grand Teton / footprints 5780-5781 of 8354")
	)
	(layers
		(0 "F.Cu" signal "TOP")
		(4 "In1.Cu" signal "GND")
		(6 "In2.Cu" signal "IN1")
		(8 "In3.Cu" signal "GND1")
		(10 "In4.Cu" signal "IN2")
		(12 "In5.Cu" signal "GND2")
		(14 "In6.Cu" signal "IN3")
		(16 "In7.Cu" signal "GND3")
		(18 "In8.Cu" signal "VCC")
		(20 "In9.Cu" signal "VCC1")
		(22 "In10.Cu" signal "GND4")
		(24 "In11.Cu" signal "IN4")
		(26 "In12.Cu" signal "GND5")
		(28 "In13.Cu" signal "IN5")
		(30 "In14.Cu" signal "GND6")
		(32 "In15.Cu" signal "IN6")
		(34 "In16.Cu" signal "GND7")
		(2 "B.Cu" signal "BOTTOM")
		(9 "F.Adhes" user "F.Adhesive")
		(11 "B.Adhes" user "B.Adhesive")
		(13 "F.Paste" user "Package Geometry/Pastemask Top")
		(15 "B.Paste" user "Package Geometry/Pastemask Bottom")
		(5 "F.SilkS" user "Ref Des/Silkscreen Top")
		(7 "B.SilkS" user "Ref Des/Silkscreen Bottom")
		(1 "F.Mask" user "Board Geometry/Soldermask Top")
		(3 "B.Mask" user "Board Geometry/Soldermask Bottom")
		(17 "Dwgs.User" user "User.Drawings")
		(19 "Cmts.User" user "User.Comments")
		(21 "Eco1.User" user "User.Eco1")
		(23 "Eco2.User" user "User.Eco2")
		(25 "Edge.Cuts" user "Board Geometry/Outline")
		(27 "Margin" user)
		(31 "F.CrtYd" user "Package Geometry/Place Bound Top")
		(29 "B.CrtYd" user "Package Geometry/Place Bound Bottom")
		(35 "F.Fab" user "Ref Des/Assembly Top")
		(33 "B.Fab" user "Ref Des/Assembly Bottom")
	)
	(footprint ""
		(layer "B.Cu")
		(at 381.291338 -398.942052 90)
		(property "Reference" "C1032"
			(at 0 0 90)
			(layer "B.SilkS")
			(hide yes)
			(effects
				(font
					(size 1.27 1.27)
				)
				(justify mirror)
			)
		)
		(property "Value" ""
			(at 0 0 90)
			(layer "B.Fab")
			(effects
				(font
					(size 1.27 1.27)
				)
				(justify mirror)
			)
		)
		(duplicate_pad_numbers_are_jumpers no)
		(fp_line
			(start 0.7874 -0.4064)
			(end -0.7874 -0.4064)
			(stroke
				(width 0.1524)
				(type default)
			)
			(layer "B.SilkS")
		)
		(fp_line
			(start -0.7874 -0.4064)
			(end -0.7874 0.4064)
			(stroke
				(width 0.1524)
				(type default)
			)
			(layer "B.SilkS")
		)
		(fp_line
			(start 0.7874 0.4064)
			(end 0.7874 -0.4064)
			(stroke
				(width 0.1524)
				(type default)
			)
			(layer "B.SilkS")
		)
		(fp_line
			(start -0.7874 0.4064)
			(end 0.7874 0.4064)
			(stroke
				(width 0.1524)
				(type default)
			)
			(layer "B.SilkS")
		)
		(fp_line
			(start 0.67945 -0.305054)
			(end 0.12065 -0.305054)
			(stroke
				(width 0.1)
				(type default)
			)
			(layer "B.Fab")
		)
		(fp_line
			(start 0.12065 -0.305054)
			(end 0.12065 -0.2794)
			(stroke
				(width 0.1)
				(type default)
			)
			(layer "B.Fab")
		)
		(fp_line
			(start -0.12065 -0.3048)
			(end -0.67945 -0.3048)
			(stroke
				(width 0.1)
				(type default)
			)
			(layer "B.Fab")
		)
		(fp_line
			(start -0.67945 -0.3048)
			(end -0.67945 0.3048)
			(stroke
				(width 0.1)
				(type default)
			)
			(layer "B.Fab")
		)
		(fp_line
			(start 0.12065 -0.2794)
			(end -0.12065 -0.2794)
			(stroke
				(width 0.1)
				(type default)
			)
			(layer "B.Fab")
		)
		(fp_line
			(start -0.12065 -0.2794)
			(end -0.12065 -0.3048)
			(stroke
				(width 0.1)
				(type default)
			)
			(layer "B.Fab")
		)
		(fp_line
			(start 0.12065 0.2794)
			(end 0.12065 0.3048)
			(stroke
				(width 0.1)
				(type default)
			)
			(layer "B.Fab")
		)
		(fp_line
			(start -0.120396 0.2794)
			(end 0.12065 0.2794)
			(stroke
				(width 0.1)
				(type default)
			)
			(layer "B.Fab")
		)
		(fp_line
			(start 0.67945 0.3048)
			(end 0.67945 -0.305054)
			(stroke
				(width 0.1)
				(type default)
			)
			(layer "B.Fab")
		)
		(fp_line
			(start 0.12065 0.3048)
			(end 0.67945 0.3048)
			(stroke
				(width 0.1)
				(type default)
			)
			(layer "B.Fab")
		)
		(fp_line
			(start -0.120396 0.3048)
			(end -0.120396 0.2794)
			(stroke
				(width 0.1)
				(type default)
			)
			(layer "B.Fab")
		)
		(fp_line
			(start -0.67945 0.3048)
			(end -0.120396 0.3048)
			(stroke
				(width 0.1)
				(type default)
			)
			(layer "B.Fab")
		)
		(pad "1" smd circle
			(at 0.40005 0 270)
			(size 0 0)
			(layers "B.Cu" "B.Mask" "B.Paste")
			(net "P0V9_CPU0_RT_2D")
		)
		(pad "2" smd circle
			(at -0.40005 0 270)
			(size 0 0)
			(layers "B.Cu" "B.Mask" "B.Paste")
			(net "GND")
		)
	)
	(footprint ""
		(layer "B.Cu")
		(at 449.443602 -422.01211 180)
		(property "Reference" "PR6814"
			(at 0 0 0)
			(layer "B.SilkS")
			(hide yes)
			(effects
				(font
					(size 1.27 1.27)
				)
				(justify mirror)
			)
		)
		(property "Value" ""
			(at 0 0 0)
			(layer "B.Fab")
			(effects
				(font
					(size 1.27 1.27)
				)
				(justify mirror)
			)
		)
		(duplicate_pad_numbers_are_jumpers no)
		(fp_line
			(start 0.7874 0.4064)
			(end 0.7874 -0.4064)
			(stroke
				(width 0.1524)
				(type default)
			)
			(layer "B.SilkS")
		)
		(fp_line
			(start 0.7874 -0.4064)
			(end -0.7874 -0.4064)
			(stroke
				(width 0.1524)
				(type default)
			)
			(layer "B.SilkS")
		)
		(fp_line
			(start -0.7874 0.4064)
			(end 0.7874 0.4064)
			(stroke
				(width 0.1524)
				(type default)
			)
			(layer "B.SilkS")
		)
		(fp_line
			(start -0.7874 -0.4064)
			(end -0.7874 0.4064)
			(stroke
				(width 0.1524)
				(type default)
			)
			(layer "B.SilkS")
		)
		(fp_line
			(start 0.67945 0.3048)
			(end 0.67945 -0.305054)
			(stroke
				(width 0.1)
				(type default)
			)
			(layer "B.Fab")
		)
		(fp_line
			(start 0.67945 -0.305054)
			(end 0.12065 -0.305054)
			(stroke
				(width 0.1)
				(type default)
			)
			(layer "B.Fab")
		)
		(fp_line
			(start 0.12065 0.3048)
			(end 0.67945 0.3048)
			(stroke
				(width 0.1)
				(type default)
			)
			(layer "B.Fab")
		)
		(fp_line
			(start 0.12065 0.2794)
			(end 0.12065 0.3048)
			(stroke
				(width 0.1)
				(type default)
			)
			(layer "B.Fab")
		)
		(fp_line
			(start 0.12065 -0.2794)
			(end -0.12065 -0.2794)
			(stroke
				(width 0.1)
				(type default)
			)
			(layer "B.Fab")
		)
		(fp_line
			(start 0.12065 -0.305054)
			(end 0.12065 -0.2794)
			(stroke
				(width 0.1)
				(type default)
			)
			(layer "B.Fab")
		)
		(fp_line
			(start -0.120396 0.3048)
			(end -0.120396 0.2794)
			(stroke
				(width 0.1)
				(type default)
			)
			(layer "B.Fab")
		)
		(fp_line
			(start -0.120396 0.2794)
			(end 0.12065 0.2794)
			(stroke
				(width 0.1)
				(type default)
			)
			(layer "B.Fab")
		)
		(fp_line
			(start -0.12065 -0.2794)
			(end -0.12065 -0.3048)
			(stroke
				(width 0.1)
				(type default)
			)
			(layer "B.Fab")
		)
		(fp_line
			(start -0.12065 -0.3048)
			(end -0.67945 -0.3048)
			(stroke
				(width 0.1)
				(type default)
			)
			(layer "B.Fab")
		)
		(fp_line
			(start -0.67945 0.3048)
			(end -0.120396 0.3048)
			(stroke
				(width 0.1)
				(type default)
			)
			(layer "B.Fab")
		)
		(fp_line
			(start -0.67945 -0.3048)
			(end -0.67945 0.3048)
			(stroke
				(width 0.1)
				(type default)
			)
			(layer "B.Fab")
		)
		(pad "1" smd circle
			(at 0.40005 0)
			(size 0 0)
			(layers "B.Cu" "B.Mask" "B.Paste")
			(net "P0V9_RETIMER_CPU0_TEMP0")
		)
		(pad "2" smd circle
			(at -0.40005 0)
			(size 0 0)
			(layers "B.Cu" "B.Mask" "B.Paste")
			(net "GND")
		)
	)
)
